(kicad_pcb
	(version 20260206)
	(generator "pcbnew")
	(generator_version "10.0")
	(general
		(thickness 1.6)
		(legacy_teardrops no)
	)
	(paper "A4")
	(title_block
		(title "03242023_DA0F0TMBIJ0_F0T_Motherboard_J_brd_V01_OCP.brd")
		(comment 1 "Grand Teton / footprints 3071-3076 of 6105")
	)
	(layers
		(0 "F.Cu" signal "TOP")
		(4 "In1.Cu" signal "GND")
		(6 "In2.Cu" signal "IN1")
		(8 "In3.Cu" signal "GND1")
		(10 "In4.Cu" signal "IN2")
		(12 "In5.Cu" signal "GND2")
		(14 "In6.Cu" signal "IN3")
		(16 "In7.Cu" signal "GND3")
		(18 "In8.Cu" signal "VCC")
		(20 "In9.Cu" signal "VCC1")
		(22 "In10.Cu" signal "GND4")
		(24 "In11.Cu" signal "IN4")
		(26 "In12.Cu" signal "GND5")
		(28 "In13.Cu" signal "IN5")
		(30 "In14.Cu" signal "GND6")
		(32 "In15.Cu" signal "IN6")
		(34 "In16.Cu" signal "GND7")
		(2 "B.Cu" signal "BOTTOM")
		(9 "F.Adhes" user "F.Adhesive")
		(11 "B.Adhes" user "B.Adhesive")
		(13 "F.Paste" user "Package Geometry/Pastemask Top")
		(15 "B.Paste" user "Package Geometry/Pastemask Bottom")
		(5 "F.SilkS" user "Ref Des/Silkscreen Top")
		(7 "B.SilkS" user "Ref Des/Silkscreen Bottom")
		(1 "F.Mask" user "Board Geometry/Soldermask Top")
		(3 "B.Mask" user "Board Geometry/Soldermask Bottom")
		(17 "Dwgs.User" user "User.Drawings")
		(19 "Cmts.User" user "User.Comments")
		(21 "Eco1.User" user "User.Eco1")
		(23 "Eco2.User" user "User.Eco2")
		(25 "Edge.Cuts" user "Board Geometry/Outline")
		(27 "Margin" user)
		(31 "F.CrtYd" user "Package Geometry/Place Bound Top")
		(29 "B.CrtYd" user "Package Geometry/Place Bound Bottom")
		(35 "F.Fab" user "Ref Des/Assembly Top")
		(33 "B.Fab" user "Ref Des/Assembly Bottom")
	)
	(footprint ""
		(layer "F.Cu")
		(at 117.904514 -333.525368 -90)
		(property "Reference" "PC525_P1_4"
			(at 0 0 270)
			(layer "F.SilkS")
			(hide yes)
			(effects
				(font
					(size 1.27 1.27)
				)
			)
		)
		(property "Value" ""
			(at 0 0 270)
			(layer "F.Fab")
			(effects
				(font
					(size 1.27 1.27)
				)
			)
		)
		(duplicate_pad_numbers_are_jumpers no)
		(fp_line
			(start -0.7874 0.4064)
			(end -0.7874 -0.4064)
			(stroke
				(width 0.1524)
				(type default)
			)
			(layer "F.SilkS")
		)
		(fp_line
			(start 0.7874 0.4064)
			(end -0.7874 0.4064)
			(stroke
				(width 0.1524)
				(type default)
			)
			(layer "F.SilkS")
		)
		(fp_line
			(start -0.7874 -0.4064)
			(end 0.7874 -0.4064)
			(stroke
				(width 0.1524)
				(type default)
			)
			(layer "F.SilkS")
		)
		(fp_line
			(start 0.7874 -0.4064)
			(end 0.7874 0.4064)
			(stroke
				(width 0.1524)
				(type default)
			)
			(layer "F.SilkS")
		)
		(fp_line
			(start -0.67945 0.3048)
			(end -0.67945 -0.305054)
			(stroke
				(width 0.1)
				(type default)
			)
			(layer "F.Fab")
		)
		(fp_line
			(start -0.12065 0.3048)
			(end -0.67945 0.3048)
			(stroke
				(width 0.1)
				(type default)
			)
			(layer "F.Fab")
		)
		(fp_line
			(start 0.120396 0.3048)
			(end 0.120396 0.2794)
			(stroke
				(width 0.1)
				(type default)
			)
			(layer "F.Fab")
		)
		(fp_line
			(start 0.67945 0.3048)
			(end 0.120396 0.3048)
			(stroke
				(width 0.1)
				(type default)
			)
			(layer "F.Fab")
		)
		(fp_line
			(start -0.12065 0.2794)
			(end -0.12065 0.3048)
			(stroke
				(width 0.1)
				(type default)
			)
			(layer "F.Fab")
		)
		(fp_line
			(start 0.120396 0.2794)
			(end -0.12065 0.2794)
			(stroke
				(width 0.1)
				(type default)
			)
			(layer "F.Fab")
		)
		(fp_line
			(start -0.12065 -0.2794)
			(end 0.12065 -0.2794)
			(stroke
				(width 0.1)
				(type default)
			)
			(layer "F.Fab")
		)
		(fp_line
			(start 0.12065 -0.2794)
			(end 0.12065 -0.3048)
			(stroke
				(width 0.1)
				(type default)
			)
			(layer "F.Fab")
		)
		(fp_line
			(start 0.12065 -0.3048)
			(end 0.67945 -0.3048)
			(stroke
				(width 0.1)
				(type default)
			)
			(layer "F.Fab")
		)
		(fp_line
			(start 0.67945 -0.3048)
			(end 0.67945 0.3048)
			(stroke
				(width 0.1)
				(type default)
			)
			(layer "F.Fab")
		)
		(fp_line
			(start -0.67945 -0.305054)
			(end -0.12065 -0.305054)
			(stroke
				(width 0.1)
				(type default)
			)
			(layer "F.Fab")
		)
		(fp_line
			(start -0.12065 -0.305054)
			(end -0.12065 -0.2794)
			(stroke
				(width 0.1)
				(type default)
			)
			(layer "F.Fab")
		)
		(pad "1" smd circle
			(at -0.40005 0 270)
			(size 0 0)
			(layers "F.Cu" "F.Mask" "F.Paste")
			(net "PVCCIN_CPU1_PVCC")
		)
		(pad "2" smd circle
			(at 0.40005 0 270)
			(size 0 0)
			(layers "F.Cu" "F.Mask" "F.Paste")
			(net "GND")
		)
	)
	(footprint ""
		(layer "F.Cu")
		(at 94.086426 -99.577398)
		(property "Reference" "Q84"
			(at -4.72948 -0.638048 0)
			(unlocked yes)
			(layer "F.SilkS")
			(effects
				(font
					(size 0.7874 0.5842)
					(thickness 0.1524)
				)
				(justify left)
			)
		)
		(property "Value" ""
			(at 0 0 0)
			(layer "F.Fab")
			(effects
				(font
					(size 1.27 1.27)
				)
			)
		)
		(duplicate_pad_numbers_are_jumpers no)
		(fp_line
			(start -1.332738 -1.100074)
			(end -0.4826 -1.100074)
			(stroke
				(width 0.1524)
				(type default)
			)
			(layer "F.SilkS")
		)
		(fp_line
			(start -1.332738 1.100074)
			(end -1.332738 -1.100074)
			(stroke
				(width 0.1524)
				(type default)
			)
			(layer "F.SilkS")
		)
		(fp_line
			(start -0.4826 -1.100074)
			(end 0 -0.541274)
			(stroke
				(width 0.1524)
				(type default)
			)
			(layer "F.SilkS")
		)
		(fp_line
			(start 0 -0.541274)
			(end 0.4826 -1.100074)
			(stroke
				(width 0.1524)
				(type default)
			)
			(layer "F.SilkS")
		)
		(fp_line
			(start 0.4826 -1.100074)
			(end 1.332738 -1.100074)
			(stroke
				(width 0.1524)
				(type default)
			)
			(layer "F.SilkS")
		)
		(fp_line
			(start 1.332738 -1.100074)
			(end 1.332738 1.100074)
			(stroke
				(width 0.1524)
				(type default)
			)
			(layer "F.SilkS")
		)
		(fp_line
			(start 1.332738 1.100074)
			(end -1.332738 1.100074)
			(stroke
				(width 0.1524)
				(type default)
			)
			(layer "F.SilkS")
		)
		(fp_poly
			(pts
				(xy -2.32918 -1.036574) (xy -1.627124 -0.685546) (xy -2.32918 -0.334518)
			)
			(stroke
				(width 0)
				(type default)
			)
			(fill yes)
			(layer "F.SilkS")
		)
		(fp_line
			(start -0.674878 -1.100074)
			(end 0.674878 -1.100074)
			(stroke
				(width 0.1)
				(type default)
			)
			(layer "F.Fab")
		)
		(fp_line
			(start -0.674878 1.100074)
			(end -0.674878 -1.100074)
			(stroke
				(width 0.1)
				(type default)
			)
			(layer "F.Fab")
		)
		(fp_line
			(start 0.674878 -1.100074)
			(end 0.674878 1.100074)
			(stroke
				(width 0.1)
				(type default)
			)
			(layer "F.Fab")
		)
		(fp_line
			(start 0.674878 1.100074)
			(end -0.674878 1.100074)
			(stroke
				(width 0.1)
				(type default)
			)
			(layer "F.Fab")
		)
		(fp_poly
			(pts
				(xy -2.2352 -0.298958) (xy -2.2352 -1.001014) (xy -1.533144 -0.649986)
			)
			(stroke
				(width 0)
				(type default)
			)
			(fill yes)
			(layer "F.Fab")
		)
		(pad "1" smd rect
			(at -0.94996 -0.649986 90)
			(size 0.4318 0.508)
			(layers "F.Cu" "F.Mask" "F.Paste")
			(net "GND")
		)
		(pad "2" smd rect
			(at -0.94996 0 90)
			(size 0.4318 0.508)
			(layers "F.Cu" "F.Mask" "F.Paste")
			(net "PWRGD_PVCCD_HV_CPU1")
		)
		(pad "3" smd rect
			(at -0.94996 0.649986 90)
			(size 0.4318 0.508)
			(layers "F.Cu" "F.Mask" "F.Paste")
			(net "LED_PWRGD_PVPP_HBM_CPU1_D")
		)
		(pad "4" smd rect
			(at 0.94996 0.649986 90)
			(size 0.4318 0.508)
			(layers "F.Cu" "F.Mask" "F.Paste")
			(net "GND")
		)
		(pad "5" smd rect
			(at 0.94996 0 90)
			(size 0.4318 0.508)
			(layers "F.Cu" "F.Mask" "F.Paste")
			(net "PWRGD_PVPP_HBM_CPU1")
		)
		(pad "6" smd rect
			(at 0.94996 -0.649986 90)
			(size 0.4318 0.508)
			(layers "F.Cu" "F.Mask" "F.Paste")
			(net "LED_PWRGD_PVCCD_HV_CPU1_D")
		)
	)
	(footprint ""
		(layer "F.Cu")
		(at 19.927824 -396.812008 -90)
		(property "Reference" "C2352"
			(at 0 0 270)
			(layer "F.SilkS")
			(hide yes)
			(effects
				(font
					(size 1.27 1.27)
				)
			)
		)
		(property "Value" ""
			(at 0 0 270)
			(layer "F.Fab")
			(effects
				(font
					(size 1.27 1.27)
				)
			)
		)
		(duplicate_pad_numbers_are_jumpers no)
		(fp_line
			(start 0.020828 0.4064)
			(end -0.7874 0.4064)
			(stroke
				(width 0.1524)
				(type default)
			)
			(layer "F.SilkS")
		)
		(fp_line
			(start -0.7874 -0.4064)
			(end 0.7874 -0.4064)
			(stroke
				(width 0.1524)
				(type default)
			)
			(layer "F.SilkS")
		)
		(fp_line
			(start 0.7874 -0.4064)
			(end 0.7874 0.4064)
			(stroke
				(width 0.1524)
				(type default)
			)
			(layer "F.SilkS")
		)
		(fp_line
			(start -0.6858 0.3048)
			(end -0.6858 -0.3048)
			(stroke
				(width 0.1)
				(type default)
			)
			(layer "F.Fab")
		)
		(fp_line
			(start -0.1016 0.3048)
			(end -0.6858 0.3048)
			(stroke
				(width 0.1)
				(type default)
			)
			(layer "F.Fab")
		)
		(fp_line
			(start 0.1016 0.3048)
			(end 0.1016 0.2794)
			(stroke
				(width 0.1)
				(type default)
			)
			(layer "F.Fab")
		)
		(fp_line
			(start 0.6858 0.3048)
			(end 0.1016 0.3048)
			(stroke
				(width 0.1)
				(type default)
			)
			(layer "F.Fab")
		)
		(fp_line
			(start -0.1016 0.2794)
			(end -0.1016 0.3048)
			(stroke
				(width 0.1)
				(type default)
			)
			(layer "F.Fab")
		)
		(fp_line
			(start 0.1016 0.2794)
			(end -0.1016 0.2794)
			(stroke
				(width 0.1)
				(type default)
			)
			(layer "F.Fab")
		)
		(fp_line
			(start -0.1016 -0.2794)
			(end 0.1016 -0.2794)
			(stroke
				(width 0.1)
				(type default)
			)
			(layer "F.Fab")
		)
		(fp_line
			(start 0.1016 -0.2794)
			(end 0.1016 -0.3048)
			(stroke
				(width 0.1)
				(type default)
			)
			(layer "F.Fab")
		)
		(fp_line
			(start -0.6858 -0.3048)
			(end -0.1016 -0.3048)
			(stroke
				(width 0.1)
				(type default)
			)
			(layer "F.Fab")
		)
		(fp_line
			(start -0.1016 -0.3048)
			(end -0.1016 -0.2794)
			(stroke
				(width 0.1)
				(type default)
			)
			(layer "F.Fab")
		)
		(fp_line
			(start 0.1016 -0.3048)
			(end 0.6858 -0.3048)
			(stroke
				(width 0.1)
				(type default)
			)
			(layer "F.Fab")
		)
		(fp_line
			(start 0.6858 -0.3048)
			(end 0.6858 0.3048)
			(stroke
				(width 0.1)
				(type default)
			)
			(layer "F.Fab")
		)
		(pad "1" smd rect
			(at -0.40005 0 90)
			(size 0.4572 0.508)
			(layers "F.Cu" "F.Mask" "F.Paste")
			(net "P2E_MB_BMC_TX_BUF2_DN<0>")
		)
		(pad "2" smd rect
			(at 0.40005 0 90)
			(size 0.4572 0.508)
			(layers "F.Cu" "F.Mask" "F.Paste")
			(net "P2E_MB_BMC_TX_BUF_C_DN<0>")
		)
	)
	(footprint ""
		(layer "F.Cu")
		(at 111.332772 -132.266182)
		(property "Reference" "R3582"
			(at 0 0 0)
			(layer "F.SilkS")
			(hide yes)
			(effects
				(font
					(size 1.27 1.27)
				)
			)
		)
		(property "Value" ""
			(at 0 0 0)
			(layer "F.Fab")
			(effects
				(font
					(size 1.27 1.27)
				)
			)
		)
		(duplicate_pad_numbers_are_jumpers no)
		(fp_line
			(start -0.7874 -0.4064)
			(end 0.7874 -0.4064)
			(stroke
				(width 0.1524)
				(type default)
			)
			(layer "F.SilkS")
		)
		(fp_line
			(start -0.7874 0.4064)
			(end -0.7874 -0.4064)
			(stroke
				(width 0.1524)
				(type default)
			)
			(layer "F.SilkS")
		)
		(fp_line
			(start 0.7874 -0.4064)
			(end 0.7874 0.4064)
			(stroke
				(width 0.1524)
				(type default)
			)
			(layer "F.SilkS")
		)
		(fp_line
			(start 0.7874 0.4064)
			(end -0.7874 0.4064)
			(stroke
				(width 0.1524)
				(type default)
			)
			(layer "F.SilkS")
		)
		(fp_line
			(start -0.67945 -0.305054)
			(end -0.12065 -0.305054)
			(stroke
				(width 0.1)
				(type default)
			)
			(layer "F.Fab")
		)
		(fp_line
			(start -0.67945 0.3048)
			(end -0.67945 -0.305054)
			(stroke
				(width 0.1)
				(type default)
			)
			(layer "F.Fab")
		)
		(fp_line
			(start -0.12065 -0.305054)
			(end -0.12065 -0.2794)
			(stroke
				(width 0.1)
				(type default)
			)
			(layer "F.Fab")
		)
		(fp_line
			(start -0.12065 -0.2794)
			(end 0.12065 -0.2794)
			(stroke
				(width 0.1)
				(type default)
			)
			(layer "F.Fab")
		)
		(fp_line
			(start -0.12065 0.2794)
			(end -0.12065 0.3048)
			(stroke
				(width 0.1)
				(type default)
			)
			(layer "F.Fab")
		)
		(fp_line
			(start -0.12065 0.3048)
			(end -0.67945 0.3048)
			(stroke
				(width 0.1)
				(type default)
			)
			(layer "F.Fab")
		)
		(fp_line
			(start 0.120396 0.2794)
			(end -0.12065 0.2794)
			(stroke
				(width 0.1)
				(type default)
			)
			(layer "F.Fab")
		)
		(fp_line
			(start 0.120396 0.3048)
			(end 0.120396 0.2794)
			(stroke
				(width 0.1)
				(type default)
			)
			(layer "F.Fab")
		)
		(fp_line
			(start 0.12065 -0.3048)
			(end 0.67945 -0.3048)
			(stroke
				(width 0.1)
				(type default)
			)
			(layer "F.Fab")
		)
		(fp_line
			(start 0.12065 -0.2794)
			(end 0.12065 -0.3048)
			(stroke
				(width 0.1)
				(type default)
			)
			(layer "F.Fab")
		)
		(fp_line
			(start 0.67945 -0.3048)
			(end 0.67945 0.3048)
			(stroke
				(width 0.1)
				(type default)
			)
			(layer "F.Fab")
		)
		(fp_line
			(start 0.67945 0.3048)
			(end 0.120396 0.3048)
			(stroke
				(width 0.1)
				(type default)
			)
			(layer "F.Fab")
		)
		(pad "1" smd circle
			(at -0.40005 0)
			(size 0 0)
			(layers "F.Cu" "F.Mask" "F.Paste")
			(net "P3V3_AUX")
		)
		(pad "2" smd circle
			(at 0.40005 0)
			(size 0 0)
			(layers "F.Cu" "F.Mask" "F.Paste")
			(net "SMB_IOEXP_3V3AUX_SCL")
		)
	)
	(footprint ""
		(layer "F.Cu")
		(at 40.389556 -400.153886 -90)
		(property "Reference" "R4648"
			(at 0 0 270)
			(layer "F.SilkS")
			(hide yes)
			(effects
				(font
					(size 1.27 1.27)
				)
			)
		)
		(property "Value" ""
			(at 0 0 270)
			(layer "F.Fab")
			(effects
				(font
					(size 1.27 1.27)
				)
			)
		)
		(duplicate_pad_numbers_are_jumpers no)
		(fp_line
			(start -0.7874 0.4064)
			(end -0.7874 -0.4064)
			(stroke
				(width 0.1524)
				(type default)
			)
			(layer "F.SilkS")
		)
		(fp_line
			(start 0.7874 0.4064)
			(end -0.7874 0.4064)
			(stroke
				(width 0.1524)
				(type default)
			)
			(layer "F.SilkS")
		)
		(fp_line
			(start -0.7874 -0.4064)
			(end 0.7874 -0.4064)
			(stroke
				(width 0.1524)
				(type default)
			)
			(layer "F.SilkS")
		)
		(fp_line
			(start 0.7874 -0.4064)
			(end 0.7874 0.4064)
			(stroke
				(width 0.1524)
				(type default)
			)
			(layer "F.SilkS")
		)
		(fp_line
			(start -0.67945 0.3048)
			(end -0.67945 -0.305054)
			(stroke
				(width 0.1)
				(type default)
			)
			(layer "F.Fab")
		)
		(fp_line
			(start -0.12065 0.3048)
			(end -0.67945 0.3048)
			(stroke
				(width 0.1)
				(type default)
			)
			(layer "F.Fab")
		)
		(fp_line
			(start 0.120396 0.3048)
			(end 0.120396 0.2794)
			(stroke
				(width 0.1)
				(type default)
			)
			(layer "F.Fab")
		)
		(fp_line
			(start 0.67945 0.3048)
			(end 0.120396 0.3048)
			(stroke
				(width 0.1)
				(type default)
			)
			(layer "F.Fab")
		)
		(fp_line
			(start -0.12065 0.2794)
			(end -0.12065 0.3048)
			(stroke
				(width 0.1)
				(type default)
			)
			(layer "F.Fab")
		)
		(fp_line
			(start 0.120396 0.2794)
			(end -0.12065 0.2794)
			(stroke
				(width 0.1)
				(type default)
			)
			(layer "F.Fab")
		)
		(fp_line
			(start -0.12065 -0.2794)
			(end 0.12065 -0.2794)
			(stroke
				(width 0.1)
				(type default)
			)
			(layer "F.Fab")
		)
		(fp_line
			(start 0.12065 -0.2794)
			(end 0.12065 -0.3048)
			(stroke
				(width 0.1)
				(type default)
			)
			(layer "F.Fab")
		)
		(fp_line
			(start 0.12065 -0.3048)
			(end 0.67945 -0.3048)
			(stroke
				(width 0.1)
				(type default)
			)
			(layer "F.Fab")
		)
		(fp_line
			(start 0.67945 -0.3048)
			(end 0.67945 0.3048)
			(stroke
				(width 0.1)
				(type default)
			)
			(layer "F.Fab")
		)
		(fp_line
			(start -0.67945 -0.305054)
			(end -0.12065 -0.305054)
			(stroke
				(width 0.1)
				(type default)
			)
			(layer "F.Fab")
		)
		(fp_line
			(start -0.12065 -0.305054)
			(end -0.12065 -0.2794)
			(stroke
				(width 0.1)
				(type default)
			)
			(layer "F.Fab")
		)
		(pad "1" smd circle
			(at -0.40005 0 270)
			(size 0 0)
			(layers "F.Cu" "F.Mask" "F.Paste")
			(net "P3V3_AUX")
		)
		(pad "2" smd circle
			(at 0.40005 0 270)
			(size 0 0)
			(layers "F.Cu" "F.Mask" "F.Paste")
			(net "FM_P2E_BUF2_EQA1")
		)
	)
	(footprint ""
		(layer "F.Cu")
		(at 194.856608 -405.102822)
		(property "Reference" "PR3916"
			(at 0 0 0)
			(layer "F.SilkS")
			(hide yes)
			(effects
				(font
					(size 1.27 1.27)
				)
			)
		)
		(property "Value" ""
			(at 0 0 0)
			(layer "F.Fab")
			(effects
				(font
					(size 1.27 1.27)
				)
			)
		)
		(duplicate_pad_numbers_are_jumpers no)
		(fp_line
			(start -0.7874 -0.4064)
			(end 0.7874 -0.4064)
			(stroke
				(width 0.1524)
				(type default)
			)
			(layer "F.SilkS")
		)
		(fp_line
			(start -0.7874 0.4064)
			(end -0.7874 -0.4064)
			(stroke
				(width 0.1524)
				(type default)
			)
			(layer "F.SilkS")
		)
		(fp_line
			(start 0.7874 -0.4064)
			(end 0.7874 0.4064)
			(stroke
				(width 0.1524)
				(type default)
			)
			(layer "F.SilkS")
		)
		(fp_line
			(start 0.7874 0.4064)
			(end -0.7874 0.4064)
			(stroke
				(width 0.1524)
				(type default)
			)
			(layer "F.SilkS")
		)
		(fp_line
			(start -0.67945 -0.305054)
			(end -0.12065 -0.305054)
			(stroke
				(width 0.1)
				(type default)
			)
			(layer "F.Fab")
		)
		(fp_line
			(start -0.67945 0.3048)
			(end -0.67945 -0.305054)
			(stroke
				(width 0.1)
				(type default)
			)
			(layer "F.Fab")
		)
		(fp_line
			(start -0.12065 -0.305054)
			(end -0.12065 -0.2794)
			(stroke
				(width 0.1)
				(type default)
			)
			(layer "F.Fab")
		)
		(fp_line
			(start -0.12065 -0.2794)
			(end 0.12065 -0.2794)
			(stroke
				(width 0.1)
				(type default)
			)
			(layer "F.Fab")
		)
		(fp_line
			(start -0.12065 0.2794)
			(end -0.12065 0.3048)
			(stroke
				(width 0.1)
				(type default)
			)
			(layer "F.Fab")
		)
		(fp_line
			(start -0.12065 0.3048)
			(end -0.67945 0.3048)
			(stroke
				(width 0.1)
				(type default)
			)
			(layer "F.Fab")
		)
		(fp_line
			(start 0.120396 0.2794)
			(end -0.12065 0.2794)
			(stroke
				(width 0.1)
				(type default)
			)
			(layer "F.Fab")
		)
		(fp_line
			(start 0.120396 0.3048)
			(end 0.120396 0.2794)
			(stroke
				(width 0.1)
				(type default)
			)
			(layer "F.Fab")
		)
		(fp_line
			(start 0.12065 -0.3048)
			(end 0.67945 -0.3048)
			(stroke
				(width 0.1)
				(type default)
			)
			(layer "F.Fab")
		)
		(fp_line
			(start 0.12065 -0.2794)
			(end 0.12065 -0.3048)
			(stroke
				(width 0.1)
				(type default)
			)
			(layer "F.Fab")
		)
		(fp_line
			(start 0.67945 -0.3048)
			(end 0.67945 0.3048)
			(stroke
				(width 0.1)
				(type default)
			)
			(layer "F.Fab")
		)
		(fp_line
			(start 0.67945 0.3048)
			(end 0.120396 0.3048)
			(stroke
				(width 0.1)
				(type default)
			)
			(layer "F.Fab")
		)
		(pad "1" smd circle
			(at -0.40005 0)
			(size 0 0)
			(layers "F.Cu" "F.Mask" "F.Paste")
			(net "HSC_SCREF")
		)
		(pad "2" smd circle
			(at 0.40005 0)
			(size 0 0)
			(layers "F.Cu" "F.Mask" "F.Paste")
			(net "HSC_SCREF_1")
		)
	)
)
